# S9S_MB_2U (Grand Teton) — schematic netlist excerpt (pin names and nets, part order shuffled) for the footprints in the layout excerpt that follows; sources: Cadence DE-HDL packaged netlist, KiCad conversion of 03242023_DA0F0TMBIJ0_F0T_Motherboard_J_brd_V01_OCP.brd

R757  Q_RES  120 1% CHIP  pkg 0402LF  page 132 : A = PVNN_TERM_CPU0 ; B = JTAG_DBP_CPU_QS_GTL_TMS
R3901  Q_RES  49.9 1% CHIP  pkg 0402LF  page 108 : A = I3C_SPD_DDREFGH_CPU1_LVC1_SCL_2 ; B = I3C_SPD_DDREFGH_CPU1_LVC1_SCL

(kicad_pcb
	(version 20260206)
	(generator "pcbnew")
	(generator_version "10.0")
	(general
		(thickness 1.6)
		(legacy_teardrops no)
	)
	(paper "A4")
	(title_block
		(title "03242023_DA0F0TMBIJ0_F0T_Motherboard_J_brd_V01_OCP.brd")
		(comment 1 "Grand Teton / footprints 6007-6008 of 6105")
	)
	(layers
		(0 "F.Cu" signal "TOP")
		(4 "In1.Cu" signal "GND")
		(6 "In2.Cu" signal "IN1")
		(8 "In3.Cu" signal "GND1")
		(10 "In4.Cu" signal "IN2")
		(12 "In5.Cu" signal "GND2")
		(14 "In6.Cu" signal "IN3")
		(16 "In7.Cu" signal "GND3")
		(18 "In8.Cu" signal "VCC")
		(20 "In9.Cu" signal "VCC1")
		(22 "In10.Cu" signal "GND4")
		(24 "In11.Cu" signal "IN4")
		(26 "In12.Cu" signal "GND5")
		(28 "In13.Cu" signal "IN5")
		(30 "In14.Cu" signal "GND6")
		(32 "In15.Cu" signal "IN6")
		(34 "In16.Cu" signal "GND7")
		(2 "B.Cu" signal "BOTTOM")
		(9 "F.Adhes" user "F.Adhesive")
		(11 "B.Adhes" user "B.Adhesive")
		(13 "F.Paste" user "Package Geometry/Pastemask Top")
		(15 "B.Paste" user "Package Geometry/Pastemask Bottom")
		(5 "F.SilkS" user "Ref Des/Silkscreen Top")
		(7 "B.SilkS" user "Ref Des/Silkscreen Bottom")
		(1 "F.Mask" user "Board Geometry/Soldermask Top")
		(3 "B.Mask" user "Board Geometry/Soldermask Bottom")
		(17 "Dwgs.User" user "User.Drawings")
		(19 "Cmts.User" user "User.Comments")
		(21 "Eco1.User" user "User.Eco1")
		(23 "Eco2.User" user "User.Eco2")
		(25 "Edge.Cuts" user "Board Geometry/Outline")
		(27 "Margin" user)
		(31 "F.CrtYd" user "Package Geometry/Place Bound Top")
		(29 "B.CrtYd" user "Package Geometry/Place Bound Bottom")
		(35 "F.Fab" user "Ref Des/Assembly Top")
		(33 "B.Fab" user "Ref Des/Assembly Bottom")
	)
	(footprint ""
		(layer "B.Cu")
		(at 181.464458 -317.26505 90)
		(property "Reference" "R3901"
			(at 0 0 90)
			(layer "B.SilkS")
			(hide yes)
			(effects
				(font
					(size 1.27 1.27)
				)
				(justify mirror)
			)
		)
		(property "Value" ""
			(at 0 0 90)
			(layer "B.Fab")
			(effects
				(font
					(size 1.27 1.27)
				)
				(justify mirror)
			)
		)
		(duplicate_pad_numbers_are_jumpers no)
		(fp_line
			(start 0.7874 -0.4064)
			(end -0.7874 -0.4064)
			(stroke
				(width 0.1524)
				(type default)
			)
			(layer "B.SilkS")
		)
		(fp_line
			(start -0.7874 -0.4064)
			(end -0.7874 0.4064)
			(stroke
				(width 0.1524)
				(type default)
			)
			(layer "B.SilkS")
		)
		(fp_line
			(start 0.7874 0.4064)
			(end 0.7874 -0.4064)
			(stroke
				(width 0.1524)
				(type default)
			)
			(layer "B.SilkS")
		)
		(fp_line
			(start -0.7874 0.4064)
			(end 0.7874 0.4064)
			(stroke
				(width 0.1524)
				(type default)
			)
			(layer "B.SilkS")
		)
		(fp_line
			(start 0.67945 -0.305054)
			(end 0.12065 -0.305054)
			(stroke
				(width 0.1)
				(type default)
			)
			(layer "B.Fab")
		)
		(fp_line
			(start 0.12065 -0.305054)
			(end 0.12065 -0.2794)
			(stroke
				(width 0.1)
				(type default)
			)
			(layer "B.Fab")
		)
		(fp_line
			(start -0.12065 -0.3048)
			(end -0.67945 -0.3048)
			(stroke
				(width 0.1)
				(type default)
			)
			(layer "B.Fab")
		)
		(fp_line
			(start -0.67945 -0.3048)
			(end -0.67945 0.3048)
			(stroke
				(width 0.1)
				(type default)
			)
			(layer "B.Fab")
		)
		(fp_line
			(start 0.12065 -0.2794)
			(end -0.12065 -0.2794)
			(stroke
				(width 0.1)
				(type default)
			)
			(layer "B.Fab")
		)
		(fp_line
			(start -0.12065 -0.2794)
			(end -0.12065 -0.3048)
			(stroke
				(width 0.1)
				(type default)
			)
			(layer "B.Fab")
		)
		(fp_line
			(start 0.12065 0.2794)
			(end 0.12065 0.3048)
			(stroke
				(width 0.1)
				(type default)
			)
			(layer "B.Fab")
		)
		(fp_line
			(start -0.120396 0.2794)
			(end 0.12065 0.2794)
			(stroke
				(width 0.1)
				(type default)
			)
			(layer "B.Fab")
		)
		(fp_line
			(start 0.67945 0.3048)
			(end 0.67945 -0.305054)
			(stroke
				(width 0.1)
				(type default)
			)
			(layer "B.Fab")
		)
		(fp_line
			(start 0.12065 0.3048)
			(end 0.67945 0.3048)
			(stroke
				(width 0.1)
				(type default)
			)
			(layer "B.Fab")
		)
		(fp_line
			(start -0.120396 0.3048)
			(end -0.120396 0.2794)
			(stroke
				(width 0.1)
				(type default)
			)
			(layer "B.Fab")
		)
		(fp_line
			(start -0.67945 0.3048)
			(end -0.120396 0.3048)
			(stroke
				(width 0.1)
				(type default)
			)
			(layer "B.Fab")
		)
		(pad "1" smd circle
			(at 0.40005 0 270)
			(size 0 0)
			(layers "B.Cu" "B.Mask" "B.Paste")
			(net "I3C_SPD_DDREFGH_CPU1_LVC1_SCL_2")
		)
		(pad "2" smd circle
			(at -0.40005 0 270)
			(size 0 0)
			(layers "B.Cu" "B.Mask" "B.Paste")
			(net "I3C_SPD_DDREFGH_CPU1_LVC1_SCL")
		)
	)
	(footprint ""
		(layer "B.Cu")
		(at 85.892894 -182.06466 -90)
		(property "Reference" "R757"
			(at 0 0 90)
			(layer "B.SilkS")
			(hide yes)
			(effects
				(font
					(size 1.27 1.27)
				)
				(justify mirror)
			)
		)
		(property "Value" ""
			(at 0 0 90)
			(layer "B.Fab")
			(effects
				(font
					(size 1.27 1.27)
				)
				(justify mirror)
			)
		)
		(duplicate_pad_numbers_are_jumpers no)
		(fp_line
			(start -0.7874 0.4064)
			(end 0.7874 0.4064)
			(stroke
				(width 0.1524)
				(type default)
			)
			(layer "B.SilkS")
		)
		(fp_line
			(start 0.7874 0.4064)
			(end 0.7874 -0.4064)
			(stroke
				(width 0.1524)
				(type default)
			)
			(layer "B.SilkS")
		)
		(fp_line
			(start -0.7874 -0.4064)
			(end -0.7874 0.4064)
			(stroke
				(width 0.1524)
				(type default)
			)
			(layer "B.SilkS")
		)
		(fp_line
			(start 0.7874 -0.4064)
			(end -0.7874 -0.4064)
			(stroke
				(width 0.1524)
				(type default)
			)
			(layer "B.SilkS")
		)
		(fp_line
			(start -0.67945 0.3048)
			(end -0.120396 0.3048)
			(stroke
				(width 0.1)
				(type default)
			)
			(layer "B.Fab")
		)
		(fp_line
			(start -0.120396 0.3048)
			(end -0.120396 0.2794)
			(stroke
				(width 0.1)
				(type default)
			)
			(layer "B.Fab")
		)
		(fp_line
			(start 0.12065 0.3048)
			(end 0.67945 0.3048)
			(stroke
				(width 0.1)
				(type default)
			)
			(layer "B.Fab")
		)
		(fp_line
			(start 0.67945 0.3048)
			(end 0.67945 -0.305054)
			(stroke
				(width 0.1)
				(type default)
			)
			(layer "B.Fab")
		)
		(fp_line
			(start -0.120396 0.2794)
			(end 0.12065 0.2794)
			(stroke
				(width 0.1)
				(type default)
			)
			(layer "B.Fab")
		)
		(fp_line
			(start 0.12065 0.2794)
			(end 0.12065 0.3048)
			(stroke
				(width 0.1)
				(type default)
			)
			(layer "B.Fab")
		)
		(fp_line
			(start -0.12065 -0.2794)
			(end -0.12065 -0.3048)
			(stroke
				(width 0.1)
				(type default)
			)
			(layer "B.Fab")
		)
		(fp_line
			(start 0.12065 -0.2794)
			(end -0.12065 -0.2794)
			(stroke
				(width 0.1)
				(type default)
			)
			(layer "B.Fab")
		)
		(fp_line
			(start -0.67945 -0.3048)
			(end -0.67945 0.3048)
			(stroke
				(width 0.1)
				(type default)
			)
			(layer "B.Fab")
		)
		(fp_line
			(start -0.12065 -0.3048)
			(end -0.67945 -0.3048)
			(stroke
				(width 0.1)
				(type default)
			)
			(layer "B.Fab")
		)
		(fp_line
			(start 0.12065 -0.305054)
			(end 0.12065 -0.2794)
			(stroke
				(width 0.1)
				(type default)
			)
			(layer "B.Fab")
		)
		(fp_line
			(start 0.67945 -0.305054)
			(end 0.12065 -0.305054)
			(stroke
				(width 0.1)
				(type default)
			)
			(layer "B.Fab")
		)
		(pad "1" smd circle
			(at 0.40005 0 90)
			(size 0 0)
			(layers "B.Cu" "B.Mask" "B.Paste")
			(net "PVNN_TERM_CPU0")
		)
		(pad "2" smd circle
			(at -0.40005 0 90)
			(size 0 0)
			(layers "B.Cu" "B.Mask" "B.Paste")
			(net "JTAG_DBP_CPU_QS_GTL_TMS")
		)
	)
)
